# BARRELEYE_G2-BPX24-EVT-HW-EBOM-X00_20161124-add_2nd_source_X09-20161207-Final.xls — DEPOP (bom)
| FOXCONN TECHNOLOGY GROUP |  |  |  |  |  |  |  |  |  |  |  |  |
| BILL OF MATERIAL |  |  |  |  |  |  |  |  |  |  |  |  |
| REV OF  BOM |  | CUSTOMER | RACKSPACE |  | CUSTOMER P/N |  | PRODUCT CODE |  | PWA  REV |  | DATE |  |
| Sourcing (Single/Sole/Multi) | Critical Commodity (Y or N) | Component Class (1, 2, other) | Customer PSL (Y or N) | Item Number | Foxconn P/N | Customer P/N | Part Description | Manufacturer  Full Name | Manufacturer  Part Number | Qty | RoHS Status | Location |
|  |  |  |  | 1 | 620101T02-015-G | - | CAP,100nF,+/-10%,X7R,16V,G,SMD0402 | MURATA ELEC. NORTH AMERICA | GRM155R71C104K | 3 |  | PSTC13,PFTC13,PETC13 |
|  |  |  |  | 2 | 61010LA00-017-G | - | RES,4.7KOhm,+/-1%,1/16W,G,SMD0402 | KOA SPEER ELECTRONICS, INC. | RK73H1ETTP4701F | 6 |  | PSTR16,PFTR16,PETR16,PSTR3005,PFTR3005,PETR3005 |
|  |  |  |  | 3 | 610107A00-017-G | - | RES,0 Ohm,+/-5%,1/16W,G,SMD0402 | KOA SPEER ELECTRONICS, INC. | RK73Z1ETTP | 43 |  | PSRR8,PSRR13,PSTR17,PFTR17,PETR17,R19,R20,R315,R329,R409,R425,R441,R457,R473,R489,R536,R537,R538,R539,R554,R574,R575,R576,R577,R615,R631,R647,R663,R679,R695,R711,R727,R743,R759,R775,R791,R807,R823,R839,R855,PSTR3014,PFTR3014,PETR3014 |
|  |  |  |  | 4 | 61100QD00-017-G |  | RES,787 Ohm,+/-0.1%,1/16W,G,SMD0402 | KOA SPEER ELECTRONICS, INC. | RN731ETTP7870B25 | 6 |  | PSTR18,PFTR18,PETR18,PSTR3015,PFTR3015,PETR3015 |
|  |  |  |  | 5 | 61100SU00-017-G |  | RES,105 Ohm,+/-0.1%,1/16W,G,SMD0402 | KOA SPEER ELECTRONICS, INC. | RN731ETTP1050B25 | 3 |  | PSTR19,PFTR19,PETR19 |
|  |  |  |  | 6 | 61012JH00-017-G |  | RES,470 Ohm,+/-5%,1/8W,G,SMD0805 | KOA SPEER ELECTRONICS, INC. | RK73B2ATTD471J | 4 |  | PSRR20,PSTR3000,PFTR3000,PETR3000 |
|  |  |  |  | 7 | 61100BP00-017-G |  | RES,3.09KOhm,+/-0.1%,1/16W,G,SMD0402 | KOA SPEER ELECTRONICS, INC. | RN731ETTP3091B25 | 3 |  | PSTR3006,PFTR3006,PETR3006 |
|  |  |  |  | 8 | 62010QB00-015-G | - | CAP,10nF,+/-10%,X7R,50V,G,SMD0402 | MURATA ELEC. NORTH AMERICA | GRM155R71H103K | 1 |  | PSRC9 |
|  |  |  |  | 9 | 620105U00-015-G | - | CAP,220pF,+/-10%,X7R,50V,G,SMD0402 | MURATA ELEC. NORTH AMERICA | GRM155R71H221K | 1 |  | PSRC13 |
|  |  |  |  | 10 | 61011HA00-017-G |  | RES,1 Ohm,+/-1%,1/16W,G,SMD0402 | KOA SPEER ELECTRONICS, INC. | RK73H1ETTP1R00F | 1 |  | PSRR14 |
|  |  |  |  | 11 | 61011MQ00-017-G | - | RES,4.75KOhm,+/-1%,1/16W,G,SMD0402 | KOA SPEER ELECTRONICS, INC. | RK73H1ETTP4751F | 1 |  | R3 |
|  |  |  |  | 12 | 61010JY00-017-G | - | RES,220 Ohm,+/-5%,1/16W,G,SMD0402 | KOA SPEER ELECTRONICS, INC. | RK73B1ETTP221J | 2 |  | R11,R13 |
|  |  |  |  | 13 | 61010G500-017-G | - | RES,10KOhm,+/-1%,1/16W,G,SMD0402 | KOA SPEER ELECTRONICS, INC. | RK73H1ETTP1002F | 24 |  | R311,R339,R419,R435,R451,R467,R483,R499,R625,R641,R657,R673,R689,R705,R721,R737,R753,R769,R785,R801,R817,R833,R849,R865 |
|  |  |  |  | 14 | 610100T00-017-G |  | RES,1KOhm,+/-5%,1/16W,G,SMD0402 | KOA SPEER ELECTRONICS, INC. | RK73B1ETTP102J | 2 |  | R520,R563 |
|  |  |  |  | 15 | 610114J00-017-G | - | RES,2KOhm,+/-1%,1/16W,G,SMD0402 | KOA SPEER ELECTRONICS, INC. | RK73H1ETTP2001F | 1 |  | R551 |
|  |  |  |  | 16 | 62010L800-015-G | - | CAP,1nF,+/-5%,NPO(C0G),50V,G,SMD0402 | MURATA ELEC. NORTH AMERICA | GRM1555C1H102J | 3 |  | PSTC5,PFTC5,PETC5 |
|  |  |  |  | 17 | 61011HA00-017-G |  | RES,1 Ohm,+/-1%,1/16W,G,SMD0402 | KOA SPEER ELECTRONICS, INC. | RK73H1ETTP1R00F | 3 |  | PSTR4,PFTR4,PETR4 |
